(kicad_pcb
	(version 20260206)
	(generator "pcbnew")
	(generator_version "10.0")
	(general
		(thickness 1.6)
		(legacy_teardrops no)
	)
	(paper "A4")
	(title_block
		(title "Bryce Canyon_F.DPB_16315-1-OCP.brd")
		(comment 1 "Bryce Canyon / footprints 89-95 of 2223")
	)
	(layers
		(0 "F.Cu" signal "TOP")
		(4 "In1.Cu" signal "L2GND")
		(6 "In2.Cu" signal "L3")
		(8 "In3.Cu" signal "L4GND")
		(10 "In4.Cu" signal "L5")
		(12 "In5.Cu" signal "L6VCC")
		(14 "In6.Cu" signal "L7VCC")
		(16 "In7.Cu" signal "L8")
		(18 "In8.Cu" signal "L9GND")
		(20 "In9.Cu" signal "L10")
		(22 "In10.Cu" signal "L11GND")
		(2 "B.Cu" signal "BOTTOM")
		(9 "F.Adhes" user "F.Adhesive")
		(11 "B.Adhes" user "B.Adhesive")
		(13 "F.Paste" user "Package Geometry/Pastemask Top")
		(15 "B.Paste" user "Package Geometry/Pastemask Bottom")
		(5 "F.SilkS" user "Ref Des/Silkscreen Top")
		(7 "B.SilkS" user "Ref Des/Silkscreen Bottom")
		(1 "F.Mask" user "Board Geometry/Soldermask Top")
		(3 "B.Mask" user "Board Geometry/Soldermask Bottom")
		(17 "Dwgs.User" user "User.Drawings")
		(19 "Cmts.User" user "User.Comments")
		(21 "Eco1.User" user "User.Eco1")
		(23 "Eco2.User" user "User.Eco2")
		(25 "Edge.Cuts" user "Board Geometry/Outline")
		(27 "Margin" user)
		(31 "F.CrtYd" user "Package Geometry/Place Bound Top")
		(29 "B.CrtYd" user "Package Geometry/Place Bound Bottom")
		(35 "F.Fab" user "Ref Des/Assembly Top")
		(33 "B.Fab" user "Ref Des/Assembly Bottom")
	)
	(footprint ""
		(layer "F.Cu")
		(at 132.752592 -298.796964)
		(property "Reference" "Q291"
			(at 0 0 0)
			(layer "F.SilkS")
			(hide yes)
			(effects
				(font
					(size 1.27 1.27)
				)
			)
		)
		(property "Value" "SSM3K324R-GP"
			(at 0.127 -8.9662 0)
			(unlocked yes)
			(layer "F.Fab")
			(hide yes)
			(effects
				(font
					(size 1.016 1.016)
					(thickness 0.1524)
				)
			)
		)
		(property "Device Type" "SOT23DGS2D4H35"
			(at 0.127 -10.4902 0)
			(unlocked yes)
			(layer "F.Fab")
			(hide yes)
			(effects
				(font
					(size 1.016 1.016)
					(thickness 0.1524)
				)
			)
		)
		(duplicate_pad_numbers_are_jumpers no)
		(fp_line
			(start -1.651 -1.778)
			(end -1.651 1.778)
			(stroke
				(width 0.1524)
				(type default)
			)
			(layer "F.SilkS")
		)
		(fp_line
			(start -1.651 1.778)
			(end 1.651 1.778)
			(stroke
				(width 0.1524)
				(type default)
			)
			(layer "F.SilkS")
		)
		(fp_line
			(start 1.651 -1.778)
			(end -1.651 -1.778)
			(stroke
				(width 0.1524)
				(type default)
			)
			(layer "F.SilkS")
		)
		(fp_line
			(start 1.651 1.778)
			(end 1.651 -1.778)
			(stroke
				(width 0.1524)
				(type default)
			)
			(layer "F.SilkS")
		)
		(fp_poly
			(pts
				(xy -1.778 1.8796) (xy -1.778 -1.8796) (xy 1.778 -1.8796) (xy 1.778 1.8796)
			)
			(stroke
				(width 0)
				(type default)
			)
			(fill no)
			(layer "F.CrtYd")
		)
		(fp_poly
			(pts
				(xy -1.778 1.8796) (xy -1.778 -1.8796) (xy 1.778 -1.8796) (xy 1.778 1.8796)
			)
			(stroke
				(width 0)
				(type default)
			)
			(fill no)
			(layer "F.Fab")
		)
		(pad "D" smd custom
			(at 0 -0.9525)
			(size 0.1905 0.1905)
			(layers "F.Cu" "F.Mask" "F.Paste")
			(net "DRV_ACT_28_N")
			(options
				(clearance outline)
				(anchor circle)
			)
			(primitives
				(gr_poly
					(pts
						(arc
							(start -0.1778 0.5715)
							(mid -0.321484 0.511984)
							(end -0.381 0.3683)
						)
						(arc
							(start -0.381 -0.3683)
							(mid -0.321484 -0.511984)
							(end -0.1778 -0.5715)
						)
						(arc
							(start 0.1778 -0.5715)
							(mid 0.321484 -0.511984)
							(end 0.381 -0.3683)
						)
						(arc
							(start 0.381 0.3683)
							(mid 0.321484 0.511984)
							(end 0.1778 0.5715)
						)
					)
					(width 0)
					(fill yes)
				)
			)
		)
		(pad "G" smd custom
			(at -0.98425 0.9525)
			(size 0.1905 0.1905)
			(layers "F.Cu" "F.Mask" "F.Paste")
			(net "DRIVE_B_28_ACT")
			(options
				(clearance outline)
				(anchor circle)
			)
			(primitives
				(gr_poly
					(pts
						(arc
							(start -0.1778 0.5715)
							(mid -0.321484 0.511984)
							(end -0.381 0.3683)
						)
						(arc
							(start -0.381 -0.3683)
							(mid -0.321484 -0.511984)
							(end -0.1778 -0.5715)
						)
						(arc
							(start 0.1778 -0.5715)
							(mid 0.321484 -0.511984)
							(end 0.381 -0.3683)
						)
						(arc
							(start 0.381 0.3683)
							(mid 0.321484 0.511984)
							(end 0.1778 0.5715)
						)
					)
					(width 0)
					(fill yes)
				)
			)
		)
		(pad "S" smd custom
			(at 0.98425 0.9525)
			(size 0.1905 0.1905)
			(layers "F.Cu" "F.Mask" "F.Paste")
			(net "GND")
			(options
				(clearance outline)
				(anchor circle)
			)
			(primitives
				(gr_poly
					(pts
						(arc
							(start -0.1778 0.5715)
							(mid -0.321484 0.511984)
							(end -0.381 0.3683)
						)
						(arc
							(start -0.381 -0.3683)
							(mid -0.321484 -0.511984)
							(end -0.1778 -0.5715)
						)
						(arc
							(start 0.1778 -0.5715)
							(mid 0.321484 -0.511984)
							(end 0.381 -0.3683)
						)
						(arc
							(start 0.381 0.3683)
							(mid 0.321484 0.511984)
							(end 0.1778 0.5715)
						)
					)
					(width 0)
					(fill yes)
				)
			)
		)
	)
	(footprint ""
		(layer "F.Cu")
		(at 361.369102 -74.335894 180)
		(property "Reference" "C450"
			(at 0 0 180)
			(layer "F.SilkS")
			(hide yes)
			(effects
				(font
					(size 1.27 1.27)
				)
			)
		)
		(property "Value" "SC1U25V3KX-GP"
			(at 0 -2.8194 180)
			(unlocked yes)
			(layer "F.Fab")
			(hide yes)
			(effects
				(font
					(size 1.016 1.016)
					(thickness 0.1524)
				)
			)
		)
		(property "Device Type" "C603H36"
			(at 0 -4.3434 180)
			(unlocked yes)
			(layer "F.Fab")
			(hide yes)
			(effects
				(font
					(size 1.016 1.016)
					(thickness 0.1524)
				)
			)
		)
		(duplicate_pad_numbers_are_jumpers no)
		(fp_line
			(start 0.508 0)
			(end -0.508 0)
			(stroke
				(width 0.2032)
				(type default)
			)
			(layer "F.SilkS")
		)
		(fp_rect
			(start -0.5842 1.3335)
			(end 0.5842 -1.3335)
			(stroke
				(width 0)
				(type default)
			)
			(fill no)
			(layer "F.CrtYd")
		)
		(fp_rect
			(start -0.5842 1.3335)
			(end 0.5842 -1.3335)
			(stroke
				(width 0)
				(type default)
			)
			(fill no)
			(layer "F.Fab")
		)
		(pad "1" smd custom
			(at 0 -0.762 180)
			(size 0.2159 0.2159)
			(layers "F.Cu" "F.Mask" "F.Paste")
			(net "P12V_HDD31")
			(options
				(clearance outline)
				(anchor circle)
			)
			(primitives
				(gr_poly
					(pts
						(arc
							(start -0.3302 -0.4318)
							(mid -0.402042 -0.402042)
							(end -0.4318 -0.3302)
						)
						(arc
							(start -0.4318 0.3302)
							(mid -0.402042 0.402042)
							(end -0.3302 0.4318)
						)
						(arc
							(start 0.3302 0.4318)
							(mid 0.402042 0.402042)
							(end 0.4318 0.3302)
						)
						(arc
							(start 0.4318 -0.3302)
							(mid 0.402042 -0.402042)
							(end 0.3302 -0.4318)
						)
					)
					(width 0)
					(fill yes)
				)
			)
		)
		(pad "2" smd custom
			(at 0 0.762 180)
			(size 0.2159 0.2159)
			(layers "F.Cu" "F.Mask" "F.Paste")
			(net "GND")
			(options
				(clearance outline)
				(anchor circle)
			)
			(primitives
				(gr_poly
					(pts
						(arc
							(start -0.3302 -0.4318)
							(mid -0.402042 -0.402042)
							(end -0.4318 -0.3302)
						)
						(arc
							(start -0.4318 0.3302)
							(mid -0.402042 0.402042)
							(end -0.3302 0.4318)
						)
						(arc
							(start 0.3302 0.4318)
							(mid 0.402042 0.402042)
							(end 0.4318 0.3302)
						)
						(arc
							(start 0.4318 -0.3302)
							(mid 0.402042 -0.402042)
							(end 0.3302 -0.4318)
						)
					)
					(width 0)
					(fill yes)
				)
			)
		)
	)
	(footprint ""
		(layer "F.Cu")
		(at 261.493 -236.855)
		(property "Reference" "U9"
			(at 0 0 0)
			(layer "F.SilkS")
			(hide yes)
			(effects
				(font
					(size 1.27 1.27)
				)
			)
		)
		(property "Value" "PCA9557PWR-1-GP-U"
			(at 0.127 -12.573 0)
			(unlocked yes)
			(layer "F.Fab")
			(hide yes)
			(effects
				(font
					(size 1.016 1.016)
					(thickness 0.1524)
				)
			)
		)
		(property "Device Type" "TSOIC16H48"
			(at 0.1016 -14.5796 0)
			(unlocked yes)
			(layer "F.Fab")
			(hide yes)
			(effects
				(font
					(size 1.016 1.016)
					(thickness 0.1524)
				)
			)
		)
		(duplicate_pad_numbers_are_jumpers no)
		(fp_line
			(start -3.0988 -1.778)
			(end -3.0988 1.778)
			(stroke
				(width 0.1524)
				(type default)
			)
			(layer "F.SilkS")
		)
		(fp_line
			(start -3.0988 -1.778)
			(end 2.3622 -1.778)
			(stroke
				(width 0.1524)
				(type default)
			)
			(layer "F.SilkS")
		)
		(fp_line
			(start -2.921 3.81)
			(end -2.921 1.778)
			(stroke
				(width 0.508)
				(type default)
			)
			(layer "F.SilkS")
		)
		(fp_line
			(start -2.54 0)
			(end -3.0988 -0.5588)
			(stroke
				(width 0.1524)
				(type default)
			)
			(layer "F.SilkS")
		)
		(fp_line
			(start -2.54 0)
			(end -3.0988 0.5588)
			(stroke
				(width 0.1524)
				(type default)
			)
			(layer "F.SilkS")
		)
		(fp_line
			(start 2.3622 -1.778)
			(end 2.3622 1.778)
			(stroke
				(width 0.1524)
				(type default)
			)
			(layer "F.SilkS")
		)
		(fp_line
			(start 2.3622 1.778)
			(end -2.921 1.778)
			(stroke
				(width 0.1524)
				(type default)
			)
			(layer "F.SilkS")
		)
		(fp_poly
			(pts
				(xy -2.4638 -1.778) (xy -2.4638 1.778) (xy 2.3622 1.778) (xy 2.3622 -1.778)
			)
			(stroke
				(width 0)
				(type default)
			)
			(fill yes)
			(layer "F.SilkS")
		)
		(fp_rect
			(start -3.175 4.064)
			(end 3.175 -4.064)
			(stroke
				(width 0)
				(type default)
			)
			(fill no)
			(layer "F.CrtYd")
		)
		(fp_poly
			(pts
				(xy -3.175 -4.064) (xy 3.175 -4.064) (xy 3.175 4.064) (xy -3.175 4.064)
			)
			(stroke
				(width 0)
				(type default)
			)
			(fill no)
			(layer "F.Fab")
		)
		(pad "1" smd rect
			(at -2.27584 2.8194)
			(size 0.3556 1.524)
			(layers "F.Cu" "F.Mask" "F.Paste")
			(net "IO_EXP3_SCL")
		)
		(pad "2" smd rect
			(at -1.6256 2.8194)
			(size 0.3556 1.524)
			(layers "F.Cu" "F.Mask" "F.Paste")
			(net "IO_EXP3_SDA")
		)
		(pad "3" smd rect
			(at -0.97536 2.8194)
			(size 0.3556 1.524)
			(layers "F.Cu" "F.Mask" "F.Paste")
			(net "IO_EXP3_A0")
		)
		(pad "4" smd rect
			(at -0.32512 2.8194)
			(size 0.3556 1.524)
			(layers "F.Cu" "F.Mask" "F.Paste")
			(net "IO_EXP3_A1")
		)
		(pad "5" smd rect
			(at 0.32512 2.8194)
			(size 0.3556 1.524)
			(layers "F.Cu" "F.Mask" "F.Paste")
			(net "IO_EXP3_A2")
		)
		(pad "6" smd rect
			(at 0.97536 2.8194)
			(size 0.3556 1.524)
			(layers "F.Cu" "F.Mask" "F.Paste")
			(net "Net_40")
		)
		(pad "7" smd rect
			(at 1.6256 2.8194)
			(size 0.3556 1.524)
			(layers "F.Cu" "F.Mask" "F.Paste")
			(net "DRIVE_A_32_PWR")
		)
		(pad "8" smd rect
			(at 2.27584 2.8194)
			(size 0.3556 1.524)
			(layers "F.Cu" "F.Mask" "F.Paste")
			(net "GND")
		)
		(pad "9" smd rect
			(at 2.27584 -2.8194)
			(size 0.3556 1.524)
			(layers "F.Cu" "F.Mask" "F.Paste")
			(net "DRIVE_A_33_PWR")
		)
		(pad "10" smd rect
			(at 1.6256 -2.8194)
			(size 0.3556 1.524)
			(layers "F.Cu" "F.Mask" "F.Paste")
			(net "DRIVE_A_34_PWR")
		)
		(pad "11" smd rect
			(at 0.97536 -2.8194)
			(size 0.3556 1.524)
			(layers "F.Cu" "F.Mask" "F.Paste")
			(net "DRIVE_A_35_PWR")
		)
		(pad "12" smd rect
			(at 0.32512 -2.8194)
			(size 0.3556 1.524)
			(layers "F.Cu" "F.Mask" "F.Paste")
			(net "Net_1270")
		)
		(pad "13" smd rect
			(at -0.32512 -2.8194)
			(size 0.3556 1.524)
			(layers "F.Cu" "F.Mask" "F.Paste")
			(net "Net_245")
		)
		(pad "14" smd rect
			(at -0.97536 -2.8194)
			(size 0.3556 1.524)
			(layers "F.Cu" "F.Mask" "F.Paste")
			(net "Net_240")
		)
		(pad "15" smd rect
			(at -1.6256 -2.8194)
			(size 0.3556 1.524)
			(layers "F.Cu" "F.Mask" "F.Paste")
			(net "IO_EXP3_INT_N")
		)
		(pad "16" smd rect
			(at -2.27584 -2.8194)
			(size 0.3556 1.524)
			(layers "F.Cu" "F.Mask" "F.Paste")
			(net "GPIO_VCC_U9")
		)
	)
	(footprint ""
		(layer "F.Cu")
		(at 241.046 -395.9098 180)
		(property "Reference" "R1163"
			(at 0 0 180)
			(layer "F.SilkS")
			(hide yes)
			(effects
				(font
					(size 1.27 1.27)
				)
			)
		)
		(property "Value" "75KR2F-GP"
			(at 0.064008 -3.993896 180)
			(unlocked yes)
			(layer "F.Fab")
			(hide yes)
			(effects
				(font
					(size 1.016 1.016)
					(thickness 0.1524)
				)
			)
		)
		(property "Device Type" "R402H16"
			(at 0.064008 -5.517896 180)
			(unlocked yes)
			(layer "F.Fab")
			(hide yes)
			(effects
				(font
					(size 1.016 1.016)
					(thickness 0.1524)
				)
			)
		)
		(duplicate_pad_numbers_are_jumpers no)
		(fp_line
			(start 0.508 -0.9398)
			(end -0.508 -0.9398)
			(stroke
				(width 0.1524)
				(type default)
			)
			(layer "F.SilkS")
		)
		(fp_line
			(start -0.508 -0.9398)
			(end -0.508 0.9398)
			(stroke
				(width 0.1524)
				(type default)
			)
			(layer "F.SilkS")
		)
		(fp_rect
			(start -0.508 0.9398)
			(end 0.508 -0.9398)
			(stroke
				(width 0)
				(type default)
			)
			(fill no)
			(layer "F.CrtYd")
		)
		(fp_rect
			(start -0.508 0.9398)
			(end 0.508 -0.9398)
			(stroke
				(width 0)
				(type default)
			)
			(fill no)
			(layer "F.Fab")
		)
		(pad "1" smd custom
			(at 0 -0.4445 180)
			(size 0.1397 0.1397)
			(layers "F.Cu" "F.Mask" "F.Paste")
			(net "MB3_ISET_R")
			(options
				(clearance outline)
				(anchor circle)
			)
			(primitives
				(gr_poly
					(pts
						(arc
							(start -0.1778 -0.2794)
							(mid -0.249642 -0.249642)
							(end -0.2794 -0.1778)
						)
						(arc
							(start -0.2794 0.1778)
							(mid -0.249642 0.249642)
							(end -0.1778 0.2794)
						)
						(arc
							(start 0.1778 0.2794)
							(mid 0.249642 0.249642)
							(end 0.2794 0.1778)
						)
						(arc
							(start 0.2794 -0.1778)
							(mid 0.249642 -0.249642)
							(end 0.1778 -0.2794)
						)
					)
					(width 0)
					(fill yes)
				)
			)
		)
		(pad "2" smd custom
			(at 0 0.4445 180)
			(size 0.1397 0.1397)
			(layers "F.Cu" "F.Mask" "F.Paste")
			(net "AGND_CURRENT_DPB")
			(options
				(clearance outline)
				(anchor circle)
			)
			(primitives
				(gr_poly
					(pts
						(arc
							(start -0.1778 -0.2794)
							(mid -0.249642 -0.249642)
							(end -0.2794 -0.1778)
						)
						(arc
							(start -0.2794 0.1778)
							(mid -0.249642 0.249642)
							(end -0.1778 0.2794)
						)
						(arc
							(start 0.1778 0.2794)
							(mid 0.249642 0.249642)
							(end 0.2794 0.1778)
						)
						(arc
							(start 0.2794 -0.1778)
							(mid 0.249642 -0.249642)
							(end 0.1778 -0.2794)
						)
					)
					(width 0)
					(fill yes)
				)
			)
		)
	)
	(footprint ""
		(layer "F.Cu")
		(at 158.708852 -277.750016 -90)
		(property "Reference" "VIA42"
			(at 0 0 270)
			(layer "F.SilkS")
			(hide yes)
			(effects
				(font
					(size 1.27 1.27)
				)
			)
		)
		(property "Value" "100OHM-8L-1D6MM-L18L16-GP"
			(at -3.7211 -4.5085 270)
			(unlocked yes)
			(layer "F.Fab")
			(hide yes)
			(effects
				(font
					(size 1.016 1.016)
					(thickness 0.1524)
				)
			)
		)
		(property "Device Type" "VIA-PCIE-4P-394076"
			(at -3.7211 -6.0325 270)
			(unlocked yes)
			(layer "F.Fab")
			(hide yes)
			(effects
				(font
					(size 1.016 1.016)
					(thickness 0.1524)
				)
			)
		)
		(duplicate_pad_numbers_are_jumpers no)
		(fp_rect
			(start -1.9685 0.381)
			(end 1.9685 -0.381)
			(stroke
				(width 0)
				(type default)
			)
			(fill no)
			(layer "F.CrtYd")
		)
		(fp_rect
			(start -1.9685 0.381)
			(end 1.9685 -0.381)
			(stroke
				(width 0)
				(type default)
			)
			(fill no)
			(layer "F.Fab")
		)
		(pad "1" thru_hole circle
			(at -1.5875 0 270)
			(size 0.508 0.508)
			(drill 0.254)
			(layers "*.Cu" "*.Mask")
			(remove_unused_layers no)
			(net "GND")
			(clearance 0.127)
			(thermal_gap 0.127)
		)
		(pad "2" thru_hole circle
			(at -0.5715 0 270)
			(size 0.508 0.508)
			(drill 0.254)
			(layers "*.Cu" "*.Mask")
			(remove_unused_layers no)
			(net "PHY_DRV_A_TO_SCC_A_4_DP")
			(clearance 0.127)
			(thermal_gap 0.127)
		)
		(pad "3" thru_hole circle
			(at 0.5715 0 270)
			(size 0.508 0.508)
			(drill 0.254)
			(layers "*.Cu" "*.Mask")
			(remove_unused_layers no)
			(net "PHY_DRV_A_TO_SCC_A_4_DN")
			(clearance 0.127)
			(thermal_gap 0.127)
		)
		(pad "4" thru_hole circle
			(at 1.5875 0 270)
			(size 0.508 0.508)
			(drill 0.254)
			(layers "*.Cu" "*.Mask")
			(remove_unused_layers no)
			(net "GND")
			(clearance 0.127)
			(thermal_gap 0.127)
		)
	)
	(footprint ""
		(layer "F.Cu")
		(at 99.278948 -65.064894 90)
		(property "Reference" "R732"
			(at 0 0 90)
			(layer "F.SilkS")
			(hide yes)
			(effects
				(font
					(size 1.27 1.27)
				)
			)
		)
		(property "Value" "220R3F-1-GP"
			(at -0.0254 -2.5146 90)
			(unlocked yes)
			(layer "F.Fab")
			(hide yes)
			(effects
				(font
					(size 1.016 1.016)
					(thickness 0.1524)
				)
			)
		)
		(property "Device Type" "R603H22"
			(at -0.0254 -4.0386 90)
			(unlocked yes)
			(layer "F.Fab")
			(hide yes)
			(effects
				(font
					(size 1.016 1.016)
					(thickness 0.1524)
				)
			)
		)
		(duplicate_pad_numbers_are_jumpers no)
		(fp_line
			(start 0.2032 0)
			(end 0.4826 0)
			(stroke
				(width 0.2032)
				(type default)
			)
			(layer "F.SilkS")
		)
		(fp_line
			(start -0.4826 0)
			(end -0.2032 0)
			(stroke
				(width 0.2032)
				(type default)
			)
			(layer "F.SilkS")
		)
		(fp_rect
			(start -0.5842 1.3335)
			(end 0.5842 -1.3335)
			(stroke
				(width 0)
				(type default)
			)
			(fill no)
			(layer "F.CrtYd")
		)
		(fp_rect
			(start -0.5842 1.3335)
			(end 0.5842 -1.3335)
			(stroke
				(width 0)
				(type default)
			)
			(fill no)
			(layer "F.Fab")
		)
		(pad "1" smd custom
			(at 0 -0.762 90)
			(size 0.2159 0.2159)
			(layers "F.Cu" "F.Mask" "F.Paste")
			(net "HDD_PRSNT_26")
			(options
				(clearance outline)
				(anchor circle)
			)
			(primitives
				(gr_poly
					(pts
						(arc
							(start -0.3302 -0.4318)
							(mid -0.402042 -0.402042)
							(end -0.4318 -0.3302)
						)
						(arc
							(start -0.4318 0.3302)
							(mid -0.402042 0.402042)
							(end -0.3302 0.4318)
						)
						(arc
							(start 0.3302 0.4318)
							(mid 0.402042 0.402042)
							(end 0.4318 0.3302)
						)
						(arc
							(start 0.4318 -0.3302)
							(mid 0.402042 -0.402042)
							(end 0.3302 -0.4318)
						)
					)
					(width 0)
					(fill yes)
				)
			)
		)
		(pad "2" smd custom
			(at 0 0.762 90)
			(size 0.2159 0.2159)
			(layers "F.Cu" "F.Mask" "F.Paste")
			(net "DRIVE_A_26_INS")
			(options
				(clearance outline)
				(anchor circle)
			)
			(primitives
				(gr_poly
					(pts
						(arc
							(start -0.3302 -0.4318)
							(mid -0.402042 -0.402042)
							(end -0.4318 -0.3302)
						)
						(arc
							(start -0.4318 0.3302)
							(mid -0.402042 0.402042)
							(end -0.3302 0.4318)
						)
						(arc
							(start 0.3302 0.4318)
							(mid 0.402042 0.402042)
							(end 0.4318 0.3302)
						)
						(arc
							(start 0.4318 -0.3302)
							(mid 0.402042 -0.402042)
							(end 0.3302 -0.4318)
						)
					)
					(width 0)
					(fill yes)
				)
			)
		)
	)
	(footprint ""
		(layer "F.Cu")
		(at 272.34007 -7.894828 180)
		(property "Reference" "TP191"
			(at 0 0 180)
			(layer "F.SilkS")
			(hide yes)
			(effects
				(font
					(size 1.27 1.27)
				)
			)
		)
		(property "Value" "TPAD32-GP"
			(at -0.0508 -1.6764 180)
			(unlocked yes)
			(layer "F.Fab")
			(hide yes)
			(effects
				(font
					(size 1.016 1.016)
					(thickness 0.1524)
				)
			)
		)
		(property "Device Type" "TPAD32"
			(at -0.0508 -3.2004 180)
			(unlocked yes)
			(layer "F.Fab")
			(hide yes)
			(effects
				(font
					(size 1.016 1.016)
					(thickness 0.1524)
				)
			)
		)
		(duplicate_pad_numbers_are_jumpers no)
		(fp_poly
			(pts
				(arc
					(start -0.4064 0)
					(mid 0.4064 0)
					(end -0.4064 0)
				)
			)
			(stroke
				(width 0)
				(type default)
			)
			(fill no)
			(layer "F.CrtYd")
		)
		(fp_poly
			(pts
				(arc
					(start -0.7112 0)
					(mid 0.7112 0)
					(end -0.7112 0)
				)
			)
			(stroke
				(width 0)
				(type default)
			)
			(fill no)
			(layer "F.Fab")
		)
		(pad "1" smd circle
			(at 0 0 180)
			(size 0.8128 0.8128)
			(layers "F.Cu" "F.Mask" "F.Paste")
			(net "TP_COMP_B_NCSI_RCLK")
		)
	)
)
